FILE_TYPE = CONNECTIVITY;
{Allegro Design Entry HDL 17.2-2016 S081 (4005846) 1/11/2022}
"PAGE_NUMBER" = 267;
0"NC";
1"P3V3_AUX\g";
2"SW_P12V_PVCCIN_CPU0_FLT\g";
3"P3V3_AUX\g";
4"PVPP_HBM_CPU0\g";
5"GND\g";
6"GND\g";
7"GND\g";
8"GND\g";
9"GND\g";
10"GND\g";
11"GND\g";
12"GND\g";
13"GND\g";
14"GND\g";
15"SH_PVPP_HBM_CPU0_P";
16"FM_HBM_VPP_SEL_CPU0_D";
17"SH_PVPP_HBM_CPU0_N";
18"FM_HBM2_HBM3_VPP_SEL";
19"PWRGD_PVPP_HBM_CPU0";
20"PWRGD_PVPP_HBM_CPU0_R"CDS_PHYS_NET_NAME"PWRGD_PVPP_HBM_CPU0_R";
21"PVPP_HBM_CPU0_FB";
22"SW_PVPP_HBM_CPU0_BST";
23"SW_PVPP_HBM_CPU0_SW";
24"PVPP_HBM_CPU0_REF";
25"PVPP_HBM_CPU0_MODE";
26"FM_PVPP_HBM_CPU0_EN";
27"PVPP_HBM_CPU0_CS";
28"PVPP_HBM_CPU0_VCC";
29"P3V3_AUX\g";
%"UNIVERSAL_GND"
"1","(-10850,2275)","0","logical_power","I1";
;
CDS_LIB"logical_power"
HDL_POWER"GND";
"A"5;
%"Q_CAP"
"1","(-10975,4350)","0","pure_quanta","I10";
;
PART_NUMBER"CH6223MEA01"
MATERIAL"X6S"
VOLTAGE"16V"
VALUE"22UF"
TOLERANCE"20%"
PACK_TYPE"C0805"
LOCATION"PC1247"
BOM_COST"VR_PCH"
CDS_LIB"pure_quanta"
$SEC"1"
CDS_SEC"1";
"B"
$PN"2"6;
"A"
$PN"1"2;
%"UNIVERSAL_GND"
"1","(-9775,2275)","0","logical_power","I11";
;
CDS_LIB"logical_power"
HDL_POWER"GND";
"A"7;
%"Q_CAP"
"1","(-10375,3400)","2","pure_quanta","I12";
;
PART_NUMBER"TMP_QCH21006JB10"
PACK_TYPE"0402"
VOLTAGE"50V"
TOLERANCE"5%"
VALUE"1000PF"
MATERIAL"EMPTY"
LOCATION"C1300"
CDS_LIB"pure_quanta"
$SEC"1"
CDS_SEC"1";
"B"
$PN"2"8;
"A"
$PN"1"26;
%"UNIVERSAL_GND"
"1","(-10275,3175)","0","logical_power","I13";
;
CDS_LIB"logical_power"
HDL_POWER"GND";
"A"8;
%"Q_RES"
"2","(-10275,3400)","0","pure_quanta","I14";
;
PART_NUMBER"CS22002FB07"
WATTAGE"1/16W"
VALUE"2K"
TOLERANCE"1%"
MATERIAL"CHIP"
PACK_TYPE"0402LF"
LOCATION"R2332"
CDS_LIB"pure_quanta"
$SEC"1"
CDS_SEC"1";
"A"
$PN"1"26;
"B"
$PN"2"8;
%"Q_RES"
"2","(-9775,2525)","0","pure_quanta","I15";
;
PART_NUMBER"CS29762FB05"
VALUE"9.76K"
MATERIAL"CHIP"
PACK_TYPE"0402LF"
WATTAGE"1/16W"
TOLERANCE"1%"
LOCATION"PR1336"
CDS_LIB"pure_quanta"
$SEC"1"
CDS_SEC"1";
"A"
$PN"1"27;
"B"
$PN"2"7;
%"Q_CAP"
"1","(-10550,4350)","0","pure_quanta","I16";
;
PART_NUMBER"CH6223MEA01"
PACK_TYPE"C0805"
VOLTAGE"16V"
VALUE"22UF"
TOLERANCE"20%"
MATERIAL"X6S"
LOCATION"PC1248"
BOM_COST"VR_PCH"
CDS_LIB"pure_quanta"
$SEC"1"
CDS_SEC"1";
"B"
$PN"2"6;
"A"
$PN"1"2;
%"Q_CAP"
"1","(-10125,4350)","0","pure_quanta","I17";
;
PART_NUMBER"CH5103KEB01"
VOLTAGE"16V"
VALUE"1UF"
PACK_TYPE"C0402"
MATERIAL"X6S"
TOLERANCE"10%"
LOCATION"PC1249"
CDS_LIB"pure_quanta"
$SEC"1"
CDS_SEC"1";
"B"
$PN"2"6;
"A"
$PN"1"2;
%"Q_RES"
"1","(-9650,3350)","0","pure_quanta","I18";
;
PART_NUMBER"CS33012FB03"
PACK_TYPE"0402LF"
WATTAGE"1/16W"
MATERIAL"CHIP"
VALUE"30.1K"
LOCATION"PR3335"
TOLERANCE"1%"
CDS_LIB"pure_quanta"
$SEC"1"
CDS_SEC"1";
"B"
$PN"2"9;
"A"
$PN"1"25;
%"RS53318LR"
"1","(-8625,3450)","0","pure_quanta","I19";
;
PART_NUMBER"AL053318002"
MATERIAL"IC"
VALUE"RS53318LR"
PART_TYPE"SMLF"
LOCATION"PU79"
SEC_TYPE""
CDS_LIB"pure_quanta"
NEEDS_NO_SIZE"TRUE"
CDS_LMAN_SYM_OUTLINE"-250,725,250,-725"
SEC"1";
"VIN2"
$PN"21"2;
"CS"
$PN"3"27;
"MODE"
$PN"4"25;
"REF"
$PN"5"24;
"SW"
$PN"20"23;
"RTN"
$PN"6"17;
"VCC"
$PN"19"28;
"AGND"
$PN"2"10;
"FB"
$PN"7"21;
"BST"
$PN"1"22;
"EN"
$PN"8"26;
"PGND"
$PN"11_18"10;
"PGOOD"
$PN"9"20;
"VIN1"
$PN"10"2;
%"UNIVERSAL_GND"
"1","(-9175,3275)","0","logical_power","I20";
;
CDS_LIB"logical_power"
HDL_POWER"GND";
"A"9;
%"VCCAUX15"
"1","(-11425,4800)","0","logical_power","I21";
;
HDL_POWER"SW_P12V_PVCCIN_CPU0_FLT"
BOM_COST"VR_PCH"
CDS_LIB"logical_power";
"A"2;
%"UNIVERSAL_GND"
"1","(-8125,2475)","0","logical_power","I22";
;
CDS_LIB"logical_power"
HDL_POWER"GND";
"A"10;
%"Q_CAP"
"1","(-8000,2575)","0","pure_quanta","I23";
;
PART_NUMBER"TMP_QCH32203KB11"
MATERIAL"X7R"
TOLERANCE"10%"
VALUE"0.022UF"
PACK_TYPE"0402"
VOLTAGE"16V"
LOCATION"PC2001"
CDS_LIB"pure_quanta"
$SEC"1"
CDS_SEC"1";
"B"
$PN"2"11;
"A"
$PN"1"24;
%"UNIVERSAL_GND"
"1","(-8000,2325)","0","logical_power","I24";
;
CDS_LIB"logical_power"
HDL_POWER"GND";
"A"11;
%"Q_CAP"
"1","(-7500,2475)","0","pure_quanta","I25";
;
PART_NUMBER"CH4104K1B00"
VALUE"0.1UF"
VOLTAGE"25V"
MATERIAL"X7R"
PACK_TYPE"0402"
TOLERANCE"10%"
LOCATION"PC1251"
CDS_LIB"pure_quanta"
$SEC"1"
CDS_SEC"1";
"B"
$PN"2"17;
"A"
$PN"1"24;
%"Q_RES"
"2","(-7000,2450)","0","pure_quanta","I26";
;
PART_NUMBER"CS31132BB02"
VALUE"11.3K"
PACK_TYPE"0402LF"
MATERIAL"CHIP"
WATTAGE"1/16W"
TOLERANCE"0.1%"
LOCATION"PR1310"
CDS_LIB"pure_quanta"
BOM_COST"VR_PCH"
$SEC"1"
CDS_SEC"1";
"A"
$PN"1"21;
"B"
$PN"2"17;
%"Q_CAP"
"1","(-7350,3850)","0","pure_quanta","I27";
;
PART_NUMBER"CH4224K1B01"
VOLTAGE"25V"
MATERIAL"X7R"
TOLERANCE"10%"
VALUE"0.22UF"
PACK_TYPE"C0402"
LOCATION"PC1252"
CDS_LIB"pure_quanta"
$SEC"1"
CDS_SEC"1";
"B"
$PN"2"23;
"A"
$PN"1"22;
%"Q_INDUCTOR"
"1","(-6525,3650)","0","pure_quanta","I28";
;
PART_NUMBER"CV+68F5MZ05"
PACK_TYPE"SMLF"
MATERIAL"IND"
VALUE"0.68UH"
LOCATION"PL118"
BOM_COST"VR_PCH"
NEEDS_NO_SIZE"TRUE"
CDS_LIB"pure_quanta"
$SEC"1"
CDS_SEC"1";
"1"
$PN"1"23;
"2"
$PN"2"4;
%"Q_RES"
"1","(-6800,4325)","0","pure_quanta","I29";
;
PART_NUMBER"CS00002JB13"
VALUE"0"
MATERIAL"CHIP"
WATTAGE"1/16W"
PACK_TYPE"0402LF"
TOLERANCE"5%"
LOCATION"R2408"
CDS_LIB"pure_quanta"
$SEC"1"
CDS_SEC"1";
"B"
$PN"2"19;
"A"
$PN"1"20;
%"VCCAUX15"
"1","(-11750,3875)","0","logical_power","I3";
;
HDL_POWER"P3V3_AUX"
CDS_LIB"logical_power"
BOM_COST"VR_PCH";
"A"1;
%"Q_CAP"
"2","(-6800,4200)","0","pure_quanta","I30";
;
PART_NUMBER"TMP_QCH21006JB10"
PACK_TYPE"0402"
VOLTAGE"50V"
MATERIAL"X7R"
VALUE"1000PF"
TOLERANCE"5%"
LOCATION"C1301"
CDS_LIB"pure_quanta"
$SEC"1"
CDS_SEC"1";
"A"
$PN"1"20;
"B"
$PN"2"12;
%"MOSFET_N"
"1","(-6275,2225)","2","pure_quanta","I31";
;
PART_NUMBER"BAM138K0000"
MATERIAL"EMPTY"
VALUE"BSS138K"
LOCATION"PU173"
PACK_TYPE"SMLF"
CDS_LIB"pure_quanta"
CDS_LMAN_SYM_OUTLINE"-50,50,100,-150"
MANUF_PN"BSS138K"
$SEC"1"
CDS_SEC"1";
"GATE"
$PN"G"18;
"SOURCE"
$PN"S"17;
"DRAIN"
$PN"D"16;
%"Q_SHORT"
"1","(-4600,1900)","0","pure_quanta","I33";
;
PART_NUMBER"SHORT6"
MATERIAL"EMPTY"
PACK_TYPE"SM"
LOCATION"PJ65"
CDS_LIB"pure_quanta"
NEEDS_NO_SIZE"TRUE"
BOM_COST"VR_PCH"
$SEC"1"
CDS_SEC"1";
"1"
$PN"1"17;
"2"
$PN"2"13;
%"Q_RES"
"1","(-6350,2475)","0","pure_quanta","I34";
;
PART_NUMBER"CS32612BB02"
WATTAGE"1/16W"
PACK_TYPE"0402LF"
TOLERANCE"0.1%"
VALUE"26.1K"
MATERIAL"EMPTY"
LOCATION"PR2336"
CDS_LIB"pure_quanta"
$SEC"1"
CDS_SEC"1";
"B"
$PN"2"16;
"A"
$PN"1"21;
%"Q_CAP"
"2","(-6350,2700)","0","pure_quanta","I35";
;
PART_NUMBER"CH1686K1B09"
VALUE"680PF"
TOLERANCE"10%"
VOLTAGE"50V"
MATERIAL"X7R"
PACK_TYPE"C0402"
LOCATION"PC1253"
CDS_LIB"pure_quanta"
$SEC"1"
CDS_SEC"1";
"A"
$PN"1"21;
"B"
$PN"2"15;
%"Q_RES"
"1","(-6400,2950)","0","pure_quanta","I36";
;
PART_NUMBER"CS33832BB06"
TOLERANCE"0.1%"
VALUE"38.3K"
WATTAGE"1/16W"
MATERIAL"CHIP"
PACK_TYPE"0402LF"
LOCATION"PR1337"
CDS_LIB"pure_quanta"
$SEC"1"
CDS_SEC"1";
"B"
$PN"2"15;
"A"
$PN"1"21;
%"UNIVERSAL_GND"
"1","(-6325,4100)","0","logical_power","I37";
;
CDS_LIB"logical_power"
HDL_POWER"GND";
"A"12;
%"Q_CAP"
"1","(-5900,3425)","0","pure_quanta","I38";
;
PART_NUMBER"CH4104K1B00"
VALUE"0.1UF"
TOLERANCE"10%"
VOLTAGE"25V"
MATERIAL"X7R"
PACK_TYPE"0402"
LOCATION"PC1254"
CDS_LIB"pure_quanta"
$SEC"1"
CDS_SEC"1";
"B"
$PN"2"14;
"A"
$PN"1"4;
%"Q_CAP"
"1","(-10850,2550)","0","pure_quanta","I4";
;
PART_NUMBER"CH5104KEB02"
PACK_TYPE"C0402"
MATERIAL"X6S"
TOLERANCE"10%"
VALUE"1UF"
VOLTAGE"25V"
LOCATION"PC2643"
CDS_LIB"pure_quanta"
SEC_TYPE"C0402"
BOM_COST"VR_PCH"
SEC"1";
"B"
$PN"2"5;
"A"
$PN"1"28;
%"Q_CAP"
"1","(-5050,2425)","0","pure_quanta","I40";
;
PART_NUMBER"TMP_QCH31004KB17"
VALUE"0.01UF"
VOLTAGE"25V"
TOLERANCE"10%"
PACK_TYPE"0402"
MATERIAL"X7R"
LOCATION"PC1421"
CDS_LIB"pure_quanta"
$SEC"1"
CDS_SEC"1";
"B"
$PN"2"17;
"A"
$PN"1"15;
%"Q_SHORT"
"1","(-4600,2875)","0","pure_quanta","I41";
;
PART_NUMBER"SHORT6"
PACK_TYPE"SM"
MATERIAL"EMPTY"
LOCATION"PJ64"
CDS_LIB"pure_quanta"
NEEDS_NO_SIZE"TRUE"
BOM_COST"VR_PCH"
$SEC"1"
CDS_SEC"1";
"1"
$PN"1"15;
"2"
$PN"2"4;
%"Q_CAP"
"1","(-5475,3425)","0","pure_quanta","I42";
;
PART_NUMBER"CH622KMEA03"
PACK_TYPE"C0805"
TOLERANCE"20%"
VOLTAGE"4V"
VALUE"22UF"
MATERIAL"X6S"
LOCATION"PC1255"
BOM_COST"VR_PCH"
CDS_LIB"pure_quanta"
$SEC"1"
CDS_SEC"1";
"B"
$PN"2"14;
"A"
$PN"1"4;
%"Q_CAP"
"1","(-5100,3425)","0","pure_quanta","I43";
;
PART_NUMBER"CH622KMEA03"
TOLERANCE"20%"
VALUE"22UF"
PACK_TYPE"C0805"
VOLTAGE"4V"
MATERIAL"X6S"
LOCATION"PC1256"
CDS_LIB"pure_quanta"
BOM_COST"VR_PCH"
$SEC"1"
CDS_SEC"1";
"B"
$PN"2"14;
"A"
$PN"1"4;
%"Q_CAP"
"1","(-4725,3425)","0","pure_quanta","I44";
;
PART_NUMBER"CH622KMEA03"
PACK_TYPE"C0805"
MATERIAL"X6S"
TOLERANCE"20%"
VALUE"22UF"
VOLTAGE"4V"
LOCATION"PC1257"
BOM_COST"VR_PCH"
CDS_LIB"pure_quanta"
$SEC"1"
CDS_SEC"1";
"B"
$PN"2"14;
"A"
$PN"1"4;
%"Q_RES"
"2","(-7225,4650)","0","pure_quanta","I45";
;
PART_NUMBER"CS31002FB08"
VALUE"10K"
WATTAGE"1/16W"
TOLERANCE"1%"
MATERIAL"CHIP"
PACK_TYPE"0402LF"
LOCATION"R2407"
CDS_LIB"pure_quanta"
BOM_COST"VR_PCH"
$SEC"1"
CDS_SEC"1";
"A"
$PN"1"3;
"B"
$PN"2"20;
%"UNIVERSAL_POWER"
"1","(-7225,4900)","0","logical_power","I46";
;
HDL_POWER"P3V3_AUX"
CDS_LIB"logical_power";
"A"3;
%"UNIVERSAL_GND"
"1","(-3900,1575)","0","logical_power","I47";
;
CDS_LIB"logical_power"
HDL_POWER"GND";
"A"13;
%"UNIVERSAL_GND"
"1","(-4325,3050)","0","logical_power","I48";
;
CDS_LIB"logical_power"
HDL_POWER"GND";
"A"14;
%"Q_CAPP"
"1","(-4325,3425)","0","pure_quanta","I49";
;
PART_NUMBER"CC75601MD16"
MATERIAL"OSCON"
PACK_TYPE"THLF"
VALUE"560UF"
TOLERANCE"20%"
VOLTAGE"6.3V"
LOCATION"PC1258"
BOM_COST"VR_PCH"
CDS_LIB"pure_quanta"
$SEC"1"
CDS_SEC"1";
"A"
$PN"1"4;
"B"
$PN"2"14;
%"Q_RES"
"2","(-10850,2975)","0","pure_quanta","I5";
;
PART_NUMBER"CS00002JB13"
PACK_TYPE"0402LF"
TOLERANCE"5%"
VALUE"0"
WATTAGE"1/16W"
MATERIAL"CHIP"
LOCATION"PR1335"
CDS_LIB"pure_quanta"
$SEC"1"
CDS_SEC"1";
"A"
$PN"1"29;
"B"
$PN"2"28;
%"UNIVERSAL_POWER"
"1","(-3900,3850)","0","logical_power","I50";
;
HDL_POWER"PVPP_HBM_CPU0"
CDS_LIB"logical_power";
"A"4;
%"UNIVERSAL_POWER"
"1","(-10850,3125)","0","logical_power","I6";
;
HDL_POWER"P3V3_AUX"
CDS_LIB"logical_power";
"A"29;
%"Q_CAP"
"1","(-11425,4350)","0","pure_quanta","I7";
;
PART_NUMBER"CH6223MEA01"
VOLTAGE"16V"
VALUE"22UF"
TOLERANCE"20%"
MATERIAL"X6S"
PACK_TYPE"C0805"
LOCATION"PC831"
BOM_COST"VR_PCH"
CDS_LIB"pure_quanta"
$SEC"1"
CDS_SEC"1";
"B"
$PN"2"6;
"A"
$PN"1"2;
%"UNIVERSAL_GND"
"1","(-11425,4000)","0","logical_power","I8";
;
CDS_LIB"logical_power"
HDL_POWER"GND";
"A"6;
%"Q_RES"
"1","(-10950,3800)","0","pure_quanta","I9";
;
PART_NUMBER"CS31002FB08"
VALUE"10K"
TOLERANCE"1%"
PACK_TYPE"0402LF"
WATTAGE"1/16W"
MATERIAL"EMPTY"
LOCATION"R2406"
CDS_LIB"pure_quanta"
$SEC"1"
CDS_SEC"1";
"B"
$PN"2"26;
"A"
$PN"1"1;
END.
